(kicad_pcb
	(version 20241229)
	(generator "pcbnew")
	(generator_version "9.0")
	(general
		(thickness 1.599998)
		(legacy_teardrops no)
	)
	(paper "A4")
	(title_block
		(date "2023-02-12")
		(rev "1.1.5")
		(comment 9 "footprint 3 of 473 (J9), pads 180-264 of 264")
	)
	(layers
		(0 "F.Cu" signal)
		(4 "In1.Cu" power "In1.GND")
		(6 "In2.Cu" signal)
		(8 "In3.Cu" power "In3.GND")
		(10 "In4.Cu" power "In4.VCC")
		(12 "In5.Cu" signal)
		(14 "In6.Cu" power "In6.VCC")
		(2 "B.Cu" signal)
		(9 "F.Adhes" user "F.Adhesive")
		(11 "B.Adhes" user "B.Adhesive")
		(13 "F.Paste" user)
		(15 "B.Paste" user)
		(5 "F.SilkS" user "F.Silkscreen")
		(7 "B.SilkS" user "B.Silkscreen")
		(1 "F.Mask" user)
		(3 "B.Mask" user)
		(17 "Dwgs.User" user "User.Drawings")
		(19 "Cmts.User" user "User.Comments")
		(21 "Eco1.User" user "User.Eco1")
		(23 "Eco2.User" user "User.Eco2")
		(25 "Edge.Cuts" user)
		(27 "Margin" user)
		(31 "F.CrtYd" user "F.Courtyard")
		(29 "B.CrtYd" user "B.Courtyard")
		(35 "F.Fab" user)
		(33 "B.Fab" user)
	)
	(footprint "antmicro-footprints:Bus_DDR4_SODIMM_TE_2309409"
		(layer "F.Cu")
		(at 150.411328 66.671157 180)
		(descr "260 pin DDR4 SODIMM Right Angle Socket, 5.2 mm (0.205 in) Stack Height, https://www.te.com/usa-en/product-2309409-1.html")
		(property "Reference" "J9"
			(at -36.726 -13.477 180)
			(layer "F.SilkS")
			(effects
				(font
					(size 0.7 0.7)
					(thickness 0.15)
				)
				(justify left bottom)
			)
		)
		(property "Value" "Bus_DDR4_SODIMM_TE_2309409"
			(at -8.1 -7.7 180)
			(layer "F.Fab")
			(effects
				(font
					(size 0.7 0.7)
					(thickness 0.15)
				)
				(justify left bottom)
			)
		)
		(property "Description" "Memory Card Connector, DDR4, SODIMM, Cam-In Locking, 260 Contacts, Copper Alloy"
			(at 0 0 180)
			(layer "F.Fab")
			(hide yes)
			(effects
				(font
					(size 1.27 1.27)
					(thickness 0.15)
				)
			)
		)
		(property "Author" "Antmicro"
			(at 300.822656 133.342314 0)
			(layer "F.Fab")
			(hide yes)
			(effects
				(font
					(size 1 1)
					(thickness 0.15)
				)
			)
		)
		(property "License" "Apache-2.0"
			(at 300.822656 133.342314 0)
			(layer "F.Fab")
			(hide yes)
			(effects
				(font
					(size 1 1)
					(thickness 0.15)
				)
			)
		)
		(property "MPN" "2309409-1"
			(at 300.822656 133.342314 0)
			(layer "F.Fab")
			(hide yes)
			(effects
				(font
					(size 1 1)
					(thickness 0.15)
				)
			)
		)
		(property "Manufacturer" "TE Connectivity"
			(at 300.822656 133.342314 0)
			(layer "F.Fab")
			(hide yes)
			(effects
				(font
					(size 1 1)
					(thickness 0.15)
				)
			)
		)
		(sheetname "SO-DIMM")
		(sheetfile "sodimm.kicad_sch")
		(attr smd)
		(pad "178" smd rect
			(at -12.875 -3.979 180)
			(size 0.3 1.75)
			(layers "F.Cu" "F.Mask" "F.Paste")
			(net 405 "IO_U5")
			(pinfunction "178")
			(pintype "passive")
		)
		(pad "179" smd rect
			(at -13.125 -12.176 180)
			(size 0.3 1.75)
			(layers "F.Cu" "F.Mask" "F.Paste")
			(net 338 "DQ15_A")
			(pinfunction "179")
			(pintype "passive")
		)
		(pad "180" smd rect
			(at -13.375 -3.979 180)
			(size 0.3 1.75)
			(layers "F.Cu" "F.Mask" "F.Paste")
			(net 400 "IO_T4")
			(pinfunction "180")
			(pintype "passive")
		)
		(pad "181" smd rect
			(at -13.625 -12.176 180)
			(size 0.3 1.75)
			(layers "F.Cu" "F.Mask" "F.Paste")
			(net 339 "DQ14_A")
			(pinfunction "181")
			(pintype "passive")
		)
		(pad "182" smd rect
			(at -13.875 -3.979 180)
			(size 0.3 1.75)
			(layers "F.Cu" "F.Mask" "F.Paste")
			(net 401 "IO_R4")
			(pinfunction "182")
			(pintype "passive")
		)
		(pad "183" smd rect
			(at -14.125 -12.176 180)
			(size 0.3 1.75)
			(layers "F.Cu" "F.Mask" "F.Paste")
			(net 340 "DQ13_A")
			(pinfunction "183")
			(pintype "passive")
		)
		(pad "184" smd rect
			(at -14.375 -3.979 180)
			(size 0.3 1.75)
			(layers "F.Cu" "F.Mask" "F.Paste")
			(net 5 "GND")
			(pinfunction "184")
			(pintype "passive")
		)
		(pad "185" smd rect
			(at -14.625 -12.176 180)
			(size 0.3 1.75)
			(layers "F.Cu" "F.Mask" "F.Paste")
			(net 341 "DQ12_A")
			(pinfunction "185")
			(pintype "passive")
		)
		(pad "186" smd rect
			(at -14.875 -3.979 180)
			(size 0.3 1.75)
			(layers "F.Cu" "F.Mask" "F.Paste")
			(net 402 "IO_P4")
			(pinfunction "186")
			(pintype "passive")
		)
		(pad "187" smd rect
			(at -15.125 -12.176 180)
			(size 0.3 1.75)
			(layers "F.Cu" "F.Mask" "F.Paste")
			(net 343 "DQ04_A")
			(pinfunction "187")
			(pintype "passive")
		)
		(pad "188" smd rect
			(at -15.375 -3.979 180)
			(size 0.3 1.75)
			(layers "F.Cu" "F.Mask" "F.Paste")
			(net 173 "unconnected-(J9-Pad188)")
			(pinfunction "188")
			(pintype "passive+no_connect")
		)
		(pad "189" smd rect
			(at -15.625 -12.176 180)
			(size 0.3 1.75)
			(layers "F.Cu" "F.Mask" "F.Paste")
			(net 344 "DQ05_A")
			(pinfunction "189")
			(pintype "passive")
		)
		(pad "190" smd rect
			(at -15.875 -3.979 180)
			(size 0.3 1.75)
			(layers "F.Cu" "F.Mask" "F.Paste")
			(net 174 "unconnected-(J9-Pad190)")
			(pinfunction "190")
			(pintype "passive+no_connect")
		)
		(pad "191" smd rect
			(at -16.125 -12.176 180)
			(size 0.3 1.75)
			(layers "F.Cu" "F.Mask" "F.Paste")
			(net 345 "DQ06_A")
			(pinfunction "191")
			(pintype "passive")
		)
		(pad "192" smd rect
			(at -16.375 -3.979 180)
			(size 0.3 1.75)
			(layers "F.Cu" "F.Mask" "F.Paste")
			(net 406 "IO_N5")
			(pinfunction "192")
			(pintype "passive")
		)
		(pad "193" smd rect
			(at -16.625 -12.176 180)
			(size 0.3 1.75)
			(layers "F.Cu" "F.Mask" "F.Paste")
			(net 346 "DQ07_A")
			(pinfunction "193")
			(pintype "passive")
		)
		(pad "194" smd rect
			(at -16.875 -3.979 180)
			(size 0.3 1.75)
			(layers "F.Cu" "F.Mask" "F.Paste")
			(net 395 "CS0_A")
			(pinfunction "194")
			(pintype "passive")
		)
		(pad "195" smd rect
			(at -17.125 -12.176 180)
			(size 0.3 1.75)
			(layers "F.Cu" "F.Mask" "F.Paste")
			(net 5 "GND")
			(pinfunction "195")
			(pintype "passive")
		)
		(pad "196" smd rect
			(at -17.375 -3.979 180)
			(size 0.3 1.75)
			(layers "F.Cu" "F.Mask" "F.Paste")
			(net 396 "CKE0_A")
			(pinfunction "196")
			(pintype "passive")
		)
		(pad "197" smd rect
			(at -17.625 -12.176 180)
			(size 0.3 1.75)
			(layers "F.Cu" "F.Mask" "F.Paste")
			(net 347 "DMI_0A")
			(pinfunction "197")
			(pintype "passive")
		)
		(pad "198" smd rect
			(at -17.875 -3.979 180)
			(size 0.3 1.75)
			(layers "F.Cu" "F.Mask" "F.Paste")
			(net 397 "IO_M5")
			(pinfunction "198")
			(pintype "passive")
		)
		(pad "199" smd rect
			(at -18.125 -12.176 180)
			(size 0.3 1.75)
			(layers "F.Cu" "F.Mask" "F.Paste")
			(net 650 "DQ_S0_N")
			(pinfunction "199")
			(pintype "passive")
		)
		(pad "200" smd rect
			(at -18.375 -3.979 180)
			(size 0.3 1.75)
			(layers "F.Cu" "F.Mask" "F.Paste")
			(net 5 "GND")
			(pinfunction "200")
			(pintype "passive")
		)
		(pad "201" smd rect
			(at -18.625 -12.176 180)
			(size 0.3 1.75)
			(layers "F.Cu" "F.Mask" "F.Paste")
			(net 651 "DQ_S0_P")
			(pinfunction "201")
			(pintype "passive")
		)
		(pad "202" smd rect
			(at -18.875 -3.979 180)
			(size 0.3 1.75)
			(layers "F.Cu" "F.Mask" "F.Paste")
			(net 175 "unconnected-(J9-Pad202)")
			(pinfunction "202")
			(pintype "passive+no_connect")
		)
		(pad "203" smd rect
			(at -19.125 -12.176 180)
			(size 0.3 1.75)
			(layers "F.Cu" "F.Mask" "F.Paste")
			(net 351 "DQ00_A")
			(pinfunction "203")
			(pintype "passive")
		)
		(pad "204" smd rect
			(at -19.375 -3.979 180)
			(size 0.3 1.75)
			(layers "F.Cu" "F.Mask" "F.Paste")
			(net 394 "CA_0A")
			(pinfunction "204")
			(pintype "passive")
		)
		(pad "205" smd rect
			(at -19.625 -12.176 180)
			(size 0.3 1.75)
			(layers "F.Cu" "F.Mask" "F.Paste")
			(net 350 "DQ01_A")
			(pinfunction "205")
			(pintype "passive")
		)
		(pad "206" smd rect
			(at -19.875 -3.979 180)
			(size 0.3 1.75)
			(layers "F.Cu" "F.Mask" "F.Paste")
			(net 393 "CA_1A")
			(pinfunction "206")
			(pintype "passive")
		)
		(pad "207" smd rect
			(at -20.125 -12.176 180)
			(size 0.3 1.75)
			(layers "F.Cu" "F.Mask" "F.Paste")
			(net 349 "DQ02_A")
			(pinfunction "207")
			(pintype "passive")
		)
		(pad "208" smd rect
			(at -20.375 -3.979 180)
			(size 0.3 1.75)
			(layers "F.Cu" "F.Mask" "F.Paste")
			(net 407 "IO_K4")
			(pinfunction "208")
			(pintype "passive")
		)
		(pad "209" smd rect
			(at -20.625 -12.176 180)
			(size 0.3 1.75)
			(layers "F.Cu" "F.Mask" "F.Paste")
			(net 348 "DQ03_A")
			(pinfunction "209")
			(pintype "passive")
		)
		(pad "210" smd rect
			(at -20.875 -3.979 180)
			(size 0.3 1.75)
			(layers "F.Cu" "F.Mask" "F.Paste")
			(net 5 "GND")
			(pinfunction "210")
			(pintype "passive")
		)
		(pad "211" smd rect
			(at -21.125 -12.176 180)
			(size 0.3 1.75)
			(layers "F.Cu" "F.Mask" "F.Paste")
			(net 5 "GND")
			(pinfunction "211")
			(pintype "passive")
		)
		(pad "212" smd rect
			(at -21.375 -3.979 180)
			(size 0.3 1.75)
			(layers "F.Cu" "F.Mask" "F.Paste")
			(net 176 "unconnected-(J9-Pad212)")
			(pinfunction "212")
			(pintype "passive+no_connect")
		)
		(pad "213" smd rect
			(at -21.625 -12.176 180)
			(size 0.3 1.75)
			(layers "F.Cu" "F.Mask" "F.Paste")
			(net 177 "unconnected-(J9-Pad213)")
			(pinfunction "213")
			(pintype "passive+no_connect")
		)
		(pad "214" smd rect
			(at -21.875 -3.979 180)
			(size 0.3 1.75)
			(layers "F.Cu" "F.Mask" "F.Paste")
			(net 178 "unconnected-(J9-Pad214)")
			(pinfunction "214")
			(pintype "passive+no_connect")
		)
		(pad "215" smd rect
			(at -22.125 -12.176 180)
			(size 0.3 1.75)
			(layers "F.Cu" "F.Mask" "F.Paste")
			(net 179 "unconnected-(J9-Pad215)")
			(pinfunction "215")
			(pintype "passive+no_connect")
		)
		(pad "216" smd rect
			(at -22.375 -3.979 180)
			(size 0.3 1.75)
			(layers "F.Cu" "F.Mask" "F.Paste")
			(net 180 "unconnected-(J9-Pad216)")
			(pinfunction "216")
			(pintype "passive+no_connect")
		)
		(pad "217" smd rect
			(at -22.625 -12.176 180)
			(size 0.3 1.75)
			(layers "F.Cu" "F.Mask" "F.Paste")
			(net 181 "unconnected-(J9-Pad217)")
			(pinfunction "217")
			(pintype "passive+no_connect")
		)
		(pad "218" smd rect
			(at -22.875 -3.979 180)
			(size 0.3 1.75)
			(layers "F.Cu" "F.Mask" "F.Paste")
			(net 182 "unconnected-(J9-Pad218)")
			(pinfunction "218")
			(pintype "passive+no_connect")
		)
		(pad "219" smd rect
			(at -23.125 -12.176 180)
			(size 0.3 1.75)
			(layers "F.Cu" "F.Mask" "F.Paste")
			(net 183 "unconnected-(J9-Pad219)")
			(pinfunction "219")
			(pintype "passive+no_connect")
		)
		(pad "220" smd rect
			(at -23.375 -3.979 180)
			(size 0.3 1.75)
			(layers "F.Cu" "F.Mask" "F.Paste")
			(net 184 "unconnected-(J9-Pad220)")
			(pinfunction "220")
			(pintype "passive+no_connect")
		)
		(pad "221" smd rect
			(at -23.625 -12.176 180)
			(size 0.3 1.75)
			(layers "F.Cu" "F.Mask" "F.Paste")
			(net 185 "unconnected-(J9-Pad221)")
			(pinfunction "221")
			(pintype "passive+no_connect")
		)
		(pad "222" smd rect
			(at -23.875 -3.979 180)
			(size 0.3 1.75)
			(layers "F.Cu" "F.Mask" "F.Paste")
			(net 186 "unconnected-(J9-Pad222)")
			(pinfunction "222")
			(pintype "passive+no_connect")
		)
		(pad "223" smd rect
			(at -24.125 -12.176 180)
			(size 0.3 1.75)
			(layers "F.Cu" "F.Mask" "F.Paste")
			(net 187 "unconnected-(J9-Pad223)")
			(pinfunction "223")
			(pintype "passive+no_connect")
		)
		(pad "224" smd rect
			(at -24.375 -3.979 180)
			(size 0.3 1.75)
			(layers "F.Cu" "F.Mask" "F.Paste")
			(net 188 "unconnected-(J9-Pad224)")
			(pinfunction "224")
			(pintype "passive+no_connect")
		)
		(pad "225" smd rect
			(at -24.625 -12.176 180)
			(size 0.3 1.75)
			(layers "F.Cu" "F.Mask" "F.Paste")
			(net 189 "unconnected-(J9-Pad225)")
			(pinfunction "225")
			(pintype "passive+no_connect")
		)
		(pad "226" smd rect
			(at -24.875 -3.979 180)
			(size 0.3 1.75)
			(layers "F.Cu" "F.Mask" "F.Paste")
			(net 190 "unconnected-(J9-Pad226)")
			(pinfunction "226")
			(pintype "passive+no_connect")
		)
		(pad "227" smd rect
			(at -25.125 -12.176 180)
			(size 0.3 1.75)
			(layers "F.Cu" "F.Mask" "F.Paste")
			(net 191 "unconnected-(J9-Pad227)")
			(pinfunction "227")
			(pintype "passive+no_connect")
		)
		(pad "228" smd rect
			(at -25.375 -3.979 180)
			(size 0.3 1.75)
			(layers "F.Cu" "F.Mask" "F.Paste")
			(net 199 "unconnected-(J9-Pad228)")
			(pinfunction "228")
			(pintype "passive+no_connect")
		)
		(pad "229" smd rect
			(at -25.625 -12.176 180)
			(size 0.3 1.75)
			(layers "F.Cu" "F.Mask" "F.Paste")
			(net 200 "unconnected-(J9-Pad229)")
			(pinfunction "229")
			(pintype "passive+no_connect")
		)
		(pad "230" smd rect
			(at -25.875 -3.979 180)
			(size 0.3 1.75)
			(layers "F.Cu" "F.Mask" "F.Paste")
			(net 201 "unconnected-(J9-Pad230)")
			(pinfunction "230")
			(pintype "passive+no_connect")
		)
		(pad "231" smd rect
			(at -26.125 -12.176 180)
			(size 0.3 1.75)
			(layers "F.Cu" "F.Mask" "F.Paste")
			(net 204 "unconnected-(J9-Pad231)")
			(pinfunction "231")
			(pintype "passive+no_connect")
		)
		(pad "232" smd rect
			(at -26.375 -3.979 180)
			(size 0.3 1.75)
			(layers "F.Cu" "F.Mask" "F.Paste")
			(net 205 "unconnected-(J9-Pad232)")
			(pinfunction "232")
			(pintype "passive+no_connect")
		)
		(pad "233" smd rect
			(at -26.625 -12.176 180)
			(size 0.3 1.75)
			(layers "F.Cu" "F.Mask" "F.Paste")
			(net 207 "unconnected-(J9-Pad233)")
			(pinfunction "233")
			(pintype "passive+no_connect")
		)
		(pad "234" smd rect
			(at -26.875 -3.979 180)
			(size 0.3 1.75)
			(layers "F.Cu" "F.Mask" "F.Paste")
			(net 214 "unconnected-(J9-Pad234)")
			(pinfunction "234")
			(pintype "passive+no_connect")
		)
		(pad "235" smd rect
			(at -27.125 -12.176 180)
			(size 0.3 1.75)
			(layers "F.Cu" "F.Mask" "F.Paste")
			(net 215 "unconnected-(J9-Pad235)")
			(pinfunction "235")
			(pintype "passive+no_connect")
		)
		(pad "236" smd rect
			(at -27.375 -3.979 180)
			(size 0.3 1.75)
			(layers "F.Cu" "F.Mask" "F.Paste")
			(net 216 "unconnected-(J9-Pad236)")
			(pinfunction "236")
			(pintype "passive+no_connect")
		)
		(pad "237" smd rect
			(at -27.625 -12.176 180)
			(size 0.3 1.75)
			(layers "F.Cu" "F.Mask" "F.Paste")
			(net 218 "unconnected-(J9-Pad237)")
			(pinfunction "237")
			(pintype "passive+no_connect")
		)
		(pad "238" smd rect
			(at -27.875 -3.979 180)
			(size 0.3 1.75)
			(layers "F.Cu" "F.Mask" "F.Paste")
			(net 220 "unconnected-(J9-Pad238)")
			(pinfunction "238")
			(pintype "passive+no_connect")
		)
		(pad "239" smd rect
			(at -28.125 -12.176 180)
			(size 0.3 1.75)
			(layers "F.Cu" "F.Mask" "F.Paste")
			(net 221 "unconnected-(J9-Pad239)")
			(pinfunction "239")
			(pintype "passive+no_connect")
		)
		(pad "240" smd rect
			(at -28.375 -3.979 180)
			(size 0.3 1.75)
			(layers "F.Cu" "F.Mask" "F.Paste")
			(net 222 "unconnected-(J9-Pad240)")
			(pinfunction "240")
			(pintype "passive+no_connect")
		)
		(pad "241" smd rect
			(at -28.625 -12.176 180)
			(size 0.3 1.75)
			(layers "F.Cu" "F.Mask" "F.Paste")
			(net 223 "unconnected-(J9-Pad241)")
			(pinfunction "241")
			(pintype "passive+no_connect")
		)
		(pad "242" smd rect
			(at -28.875 -3.979 180)
			(size 0.3 1.75)
			(layers "F.Cu" "F.Mask" "F.Paste")
			(net 225 "unconnected-(J9-Pad242)")
			(pinfunction "242")
			(pintype "passive+no_connect")
		)
		(pad "243" smd rect
			(at -29.125 -12.176 180)
			(size 0.3 1.75)
			(layers "F.Cu" "F.Mask" "F.Paste")
			(net 226 "unconnected-(J9-Pad243)")
			(pinfunction "243")
			(pintype "passive+no_connect")
		)
		(pad "244" smd rect
			(at -29.375 -3.979 180)
			(size 0.3 1.75)
			(layers "F.Cu" "F.Mask" "F.Paste")
			(net 227 "unconnected-(J9-Pad244)")
			(pinfunction "244")
			(pintype "passive+no_connect")
		)
		(pad "245" smd rect
			(at -29.625 -12.176 180)
			(size 0.3 1.75)
			(layers "F.Cu" "F.Mask" "F.Paste")
			(net 273 "1V1_DDR")
			(pinfunction "245")
			(pintype "passive")
		)
		(pad "246" smd rect
			(at -29.875 -3.979 180)
			(size 0.3 1.75)
			(layers "F.Cu" "F.Mask" "F.Paste")
			(net 66 "VDDQ")
			(pinfunction "246")
			(pintype "passive")
		)
		(pad "247" smd rect
			(at -30.125 -12.176 180)
			(size 0.3 1.75)
			(layers "F.Cu" "F.Mask" "F.Paste")
			(net 273 "1V1_DDR")
			(pinfunction "247")
			(pintype "passive")
		)
		(pad "248" smd rect
			(at -30.375 -3.979 180)
			(size 0.3 1.75)
			(layers "F.Cu" "F.Mask" "F.Paste")
			(net 66 "VDDQ")
			(pinfunction "248")
			(pintype "passive")
		)
		(pad "249" smd rect
			(at -30.625 -12.176 180)
			(size 0.3 1.75)
			(layers "F.Cu" "F.Mask" "F.Paste")
			(net 273 "1V1_DDR")
			(pinfunction "249")
			(pintype "passive")
		)
		(pad "250" smd rect
			(at -30.875 -3.979 180)
			(size 0.3 1.75)
			(layers "F.Cu" "F.Mask" "F.Paste")
			(net 66 "VDDQ")
			(pinfunction "250")
			(pintype "passive")
		)
		(pad "251" smd rect
			(at -31.125 -12.176 180)
			(size 0.3 1.75)
			(layers "F.Cu" "F.Mask" "F.Paste")
			(net 273 "1V1_DDR")
			(pinfunction "251")
			(pintype "passive")
		)
		(pad "252" smd rect
			(at -31.375 -3.979 180)
			(size 0.3 1.75)
			(layers "F.Cu" "F.Mask" "F.Paste")
			(net 641 "1V8_DDR")
			(pinfunction "252")
			(pintype "passive")
		)
		(pad "253" smd rect
			(at -31.625 -12.176 180)
			(size 0.3 1.75)
			(layers "F.Cu" "F.Mask" "F.Paste")
			(net 273 "1V1_DDR")
			(pinfunction "253")
			(pintype "passive")
		)
		(pad "254" smd rect
			(at -31.875 -3.979 180)
			(size 0.3 1.75)
			(layers "F.Cu" "F.Mask" "F.Paste")
			(net 641 "1V8_DDR")
			(pinfunction "254")
			(pintype "passive")
		)
		(pad "255" smd rect
			(at -32.125 -12.176 180)
			(size 0.3 1.75)
			(layers "F.Cu" "F.Mask" "F.Paste")
			(net 273 "1V1_DDR")
			(pinfunction "255")
			(pintype "passive")
		)
		(pad "256" smd rect
			(at -32.375 -3.979 180)
			(size 0.3 1.75)
			(layers "F.Cu" "F.Mask" "F.Paste")
			(net 641 "1V8_DDR")
			(pinfunction "256")
			(pintype "passive")
		)
		(pad "257" smd rect
			(at -32.625 -12.176 180)
			(size 0.3 1.75)
			(layers "F.Cu" "F.Mask" "F.Paste")
			(net 273 "1V1_DDR")
			(pinfunction "257")
			(pintype "passive")
		)
		(pad "258" smd rect
			(at -32.875 -3.979 180)
			(size 0.3 1.75)
			(layers "F.Cu" "F.Mask" "F.Paste")
			(net 641 "1V8_DDR")
			(pinfunction "258")
			(pintype "passive")
		)
		(pad "259" smd rect
			(at -33.125 -12.176 180)
			(size 0.3 1.75)
			(layers "F.Cu" "F.Mask" "F.Paste")
			(net 273 "1V1_DDR")
			(pinfunction "259")
			(pintype "passive")
		)
		(pad "260" smd rect
			(at -33.375 -3.979 180)
			(size 0.3 1.75)
			(layers "F.Cu" "F.Mask" "F.Paste")
			(net 641 "1V8_DDR")
			(pinfunction "260")
			(pintype "passive")
		)
		(pad "S1" smd rect
			(at 33.798 3.925 180)
			(size 3.5 4.6)
			(layers "F.Cu" "F.Mask" "F.Paste")
			(net 5 "GND")
			(pinfunction "SHIELD")
			(pintype "passive")
		)
		(pad "S2" smd rect
			(at -33.8 3.925 180)
			(size 3.5 4.6)
			(layers "F.Cu" "F.Mask" "F.Paste")
			(net 5 "GND")
			(pinfunction "SHIELD")
			(pintype "passive")
		)
	)
)
